(kicad_pcb
	(version 20260206)
	(generator "pcbnew")
	(generator_version "10.0")
	(general
		(thickness 1.6)
		(legacy_teardrops no)
	)
	(paper "A4")
	(title_block
		(title "baseboard — 13948-1b.1110WZS1818.brd")
		(comment 1 "Honey Badger (Wiwynn) / footprints 175-181 of 2523")
	)
	(layers
		(0 "F.Cu" signal "TOP")
		(4 "In1.Cu" signal "L2GND")
		(6 "In2.Cu" signal "L3")
		(8 "In3.Cu" signal "L4VCC")
		(10 "In4.Cu" signal "L5VCC")
		(12 "In5.Cu" signal "L6")
		(14 "In6.Cu" signal "L7GND")
		(2 "B.Cu" signal "BOTTOM")
		(9 "F.Adhes" user "F.Adhesive")
		(11 "B.Adhes" user "B.Adhesive")
		(13 "F.Paste" user "Package Geometry/Pastemask Top")
		(15 "B.Paste" user "Package Geometry/Pastemask Bottom")
		(5 "F.SilkS" user "Ref Des/Silkscreen Top")
		(7 "B.SilkS" user "Ref Des/Silkscreen Bottom")
		(1 "F.Mask" user "Board Geometry/Soldermask Top")
		(3 "B.Mask" user "Board Geometry/Soldermask Bottom")
		(17 "Dwgs.User" user "User.Drawings")
		(19 "Cmts.User" user "User.Comments")
		(21 "Eco1.User" user "User.Eco1")
		(23 "Eco2.User" user "User.Eco2")
		(25 "Edge.Cuts" user "Board Geometry/Outline")
		(27 "Margin" user)
		(31 "F.CrtYd" user "Package Geometry/Place Bound Top")
		(29 "B.CrtYd" user "Package Geometry/Place Bound Bottom")
		(35 "F.Fab" user "Ref Des/Assembly Top")
		(33 "B.Fab" user "Ref Des/Assembly Bottom")
	)
	(footprint ""
		(layer "F.Cu")
		(at 183.896 -122.047)
		(property "Reference" "C329"
			(at 0 0 0)
			(layer "F.SilkS")
			(hide yes)
			(effects
				(font
					(size 1.27 1.27)
				)
			)
		)
		(property "Value" "SCD1U25V2KX-2-GP"
			(at 1.1811 -2.7051 0)
			(unlocked yes)
			(layer "F.Fab")
			(hide yes)
			(effects
				(font
					(size 1.016 1.016)
					(thickness 0.1524)
				)
			)
		)
		(property "Device Type" "C402H22"
			(at 1.1811 -4.2291 0)
			(unlocked yes)
			(layer "F.Fab")
			(hide yes)
			(effects
				(font
					(size 1.016 1.016)
					(thickness 0.1524)
				)
			)
		)
		(duplicate_pad_numbers_are_jumpers no)
		(fp_rect
			(start -0.4318 0.9525)
			(end 0.4318 -0.9525)
			(stroke
				(width 0)
				(type default)
			)
			(fill no)
			(layer "F.CrtYd")
		)
		(fp_rect
			(start -0.4318 0.9525)
			(end 0.4318 -0.9525)
			(stroke
				(width 0)
				(type default)
			)
			(fill no)
			(layer "F.Fab")
		)
		(pad "1" smd custom
			(at 0 -0.4445)
			(size 0.1524 0.1524)
			(layers "F.Cu" "F.Mask" "F.Paste")
			(net "P3V3_STBY")
			(options
				(clearance outline)
				(anchor circle)
			)
			(primitives
				(gr_poly
					(pts
						(arc
							(start 0.3048 -0.2032)
							(mid 0.275042 -0.275042)
							(end 0.2032 -0.3048)
						)
						(arc
							(start -0.2032 -0.3048)
							(mid -0.275042 -0.275042)
							(end -0.3048 -0.2032)
						)
						(arc
							(start -0.3048 0.2032)
							(mid -0.275042 0.275042)
							(end -0.2032 0.3048)
						)
						(arc
							(start 0.2032 0.3048)
							(mid 0.275042 0.275042)
							(end 0.3048 0.2032)
						)
					)
					(width 0)
					(fill yes)
				)
			)
		)
		(pad "2" smd custom
			(at 0 0.4445)
			(size 0.1524 0.1524)
			(layers "F.Cu" "F.Mask" "F.Paste")
			(net "GND")
			(options
				(clearance outline)
				(anchor circle)
			)
			(primitives
				(gr_poly
					(pts
						(arc
							(start 0.3048 -0.2032)
							(mid 0.275042 -0.275042)
							(end 0.2032 -0.3048)
						)
						(arc
							(start -0.2032 -0.3048)
							(mid -0.275042 -0.275042)
							(end -0.3048 -0.2032)
						)
						(arc
							(start -0.3048 0.2032)
							(mid -0.275042 0.275042)
							(end -0.2032 0.3048)
						)
						(arc
							(start 0.2032 0.3048)
							(mid 0.275042 0.275042)
							(end 0.3048 0.2032)
						)
					)
					(width 0)
					(fill yes)
				)
			)
		)
	)
	(footprint ""
		(layer "F.Cu")
		(at 264.541 -26.797 -90)
		(property "Reference" "PC55"
			(at 0 0 270)
			(layer "F.SilkS")
			(hide yes)
			(effects
				(font
					(size 1.27 1.27)
				)
			)
		)
		(property "Value" "SCD1U16V3KX-3GP"
			(at 0 -2.8194 270)
			(unlocked yes)
			(layer "F.Fab")
			(hide yes)
			(effects
				(font
					(size 1.016 1.016)
					(thickness 0.1524)
				)
			)
		)
		(property "Device Type" "C603H36"
			(at 0 -4.3434 270)
			(unlocked yes)
			(layer "F.Fab")
			(hide yes)
			(effects
				(font
					(size 1.016 1.016)
					(thickness 0.1524)
				)
			)
		)
		(duplicate_pad_numbers_are_jumpers no)
		(fp_line
			(start 0.508 0)
			(end -0.508 0)
			(stroke
				(width 0.2032)
				(type default)
			)
			(layer "F.SilkS")
		)
		(fp_rect
			(start -0.5842 1.3335)
			(end 0.5842 -1.3335)
			(stroke
				(width 0)
				(type default)
			)
			(fill no)
			(layer "F.CrtYd")
		)
		(fp_rect
			(start -0.5842 1.3335)
			(end 0.5842 -1.3335)
			(stroke
				(width 0)
				(type default)
			)
			(fill no)
			(layer "F.Fab")
		)
		(pad "1" smd custom
			(at 0 -0.762 270)
			(size 0.2159 0.2159)
			(layers "F.Cu" "F.Mask" "F.Paste")
			(net "P1V8_STBY")
			(options
				(clearance outline)
				(anchor circle)
			)
			(primitives
				(gr_poly
					(pts
						(arc
							(start -0.3302 -0.4318)
							(mid -0.402042 -0.402042)
							(end -0.4318 -0.3302)
						)
						(arc
							(start -0.4318 0.3302)
							(mid -0.402042 0.402042)
							(end -0.3302 0.4318)
						)
						(arc
							(start 0.3302 0.4318)
							(mid 0.402042 0.402042)
							(end 0.4318 0.3302)
						)
						(arc
							(start 0.4318 -0.3302)
							(mid 0.402042 -0.402042)
							(end 0.3302 -0.4318)
						)
					)
					(width 0)
					(fill yes)
				)
			)
		)
		(pad "2" smd custom
			(at 0 0.762 270)
			(size 0.2159 0.2159)
			(layers "F.Cu" "F.Mask" "F.Paste")
			(net "GND")
			(options
				(clearance outline)
				(anchor circle)
			)
			(primitives
				(gr_poly
					(pts
						(arc
							(start -0.3302 -0.4318)
							(mid -0.402042 -0.402042)
							(end -0.4318 -0.3302)
						)
						(arc
							(start -0.4318 0.3302)
							(mid -0.402042 0.402042)
							(end -0.3302 0.4318)
						)
						(arc
							(start 0.3302 0.4318)
							(mid 0.402042 0.402042)
							(end 0.4318 0.3302)
						)
						(arc
							(start 0.4318 -0.3302)
							(mid 0.402042 -0.402042)
							(end 0.3302 -0.4318)
						)
					)
					(width 0)
					(fill yes)
				)
			)
		)
	)
	(footprint ""
		(layer "F.Cu")
		(at 51.308 -204.978 -90)
		(property "Reference" "Q93"
			(at 0 0 270)
			(layer "F.SilkS")
			(hide yes)
			(effects
				(font
					(size 1.27 1.27)
				)
			)
		)
		(property "Value" "2N7002A-7-GP"
			(at 0.127 -8.9662 270)
			(unlocked yes)
			(layer "F.Fab")
			(hide yes)
			(effects
				(font
					(size 1.016 1.016)
					(thickness 0.1524)
				)
			)
		)
		(property "Device Type" "SOT23DGS2D4H48"
			(at 0.127 -10.4902 270)
			(unlocked yes)
			(layer "F.Fab")
			(hide yes)
			(effects
				(font
					(size 1.016 1.016)
					(thickness 0.1524)
				)
			)
		)
		(duplicate_pad_numbers_are_jumpers no)
		(fp_line
			(start -1.651 1.778)
			(end 1.651 1.778)
			(stroke
				(width 0.1524)
				(type default)
			)
			(layer "F.SilkS")
		)
		(fp_line
			(start 1.651 1.778)
			(end 1.651 -1.778)
			(stroke
				(width 0.1524)
				(type default)
			)
			(layer "F.SilkS")
		)
		(fp_line
			(start -1.651 -1.778)
			(end -1.651 1.778)
			(stroke
				(width 0.1524)
				(type default)
			)
			(layer "F.SilkS")
		)
		(fp_line
			(start 1.651 -1.778)
			(end -1.651 -1.778)
			(stroke
				(width 0.1524)
				(type default)
			)
			(layer "F.SilkS")
		)
		(fp_poly
			(pts
				(xy -1.778 1.8796) (xy -1.778 -1.8796) (xy 1.778 -1.8796) (xy 1.778 1.8796)
			)
			(stroke
				(width 0)
				(type default)
			)
			(fill no)
			(layer "F.CrtYd")
		)
		(fp_poly
			(pts
				(xy -1.778 1.8796) (xy -1.778 -1.8796) (xy 1.778 -1.8796) (xy 1.778 1.8796)
			)
			(stroke
				(width 0)
				(type default)
			)
			(fill no)
			(layer "F.Fab")
		)
		(pad "D" smd custom
			(at 0 -0.9525 270)
			(size 0.1905 0.1905)
			(layers "F.Cu" "F.Mask" "F.Paste")
			(net "MATED_P12V_EN")
			(options
				(clearance outline)
				(anchor circle)
			)
			(primitives
				(gr_poly
					(pts
						(arc
							(start -0.1778 0.5715)
							(mid -0.321484 0.511984)
							(end -0.381 0.3683)
						)
						(arc
							(start -0.381 -0.3683)
							(mid -0.321484 -0.511984)
							(end -0.1778 -0.5715)
						)
						(arc
							(start 0.1778 -0.5715)
							(mid 0.321484 -0.511984)
							(end 0.381 -0.3683)
						)
						(arc
							(start 0.381 0.3683)
							(mid 0.321484 0.511984)
							(end 0.1778 0.5715)
						)
					)
					(width 0)
					(fill yes)
				)
			)
		)
		(pad "G" smd custom
			(at -0.98425 0.9525 270)
			(size 0.1905 0.1905)
			(layers "F.Cu" "F.Mask" "F.Paste")
			(net "PCIE_MATED#_B")
			(options
				(clearance outline)
				(anchor circle)
			)
			(primitives
				(gr_poly
					(pts
						(arc
							(start -0.1778 0.5715)
							(mid -0.321484 0.511984)
							(end -0.381 0.3683)
						)
						(arc
							(start -0.381 -0.3683)
							(mid -0.321484 -0.511984)
							(end -0.1778 -0.5715)
						)
						(arc
							(start 0.1778 -0.5715)
							(mid 0.321484 -0.511984)
							(end 0.381 -0.3683)
						)
						(arc
							(start 0.381 0.3683)
							(mid 0.321484 0.511984)
							(end 0.1778 0.5715)
						)
					)
					(width 0)
					(fill yes)
				)
			)
		)
		(pad "S" smd custom
			(at 0.98425 0.9525 270)
			(size 0.1905 0.1905)
			(layers "F.Cu" "F.Mask" "F.Paste")
			(net "GND")
			(options
				(clearance outline)
				(anchor circle)
			)
			(primitives
				(gr_poly
					(pts
						(arc
							(start -0.1778 0.5715)
							(mid -0.321484 0.511984)
							(end -0.381 0.3683)
						)
						(arc
							(start -0.381 -0.3683)
							(mid -0.321484 -0.511984)
							(end -0.1778 -0.5715)
						)
						(arc
							(start 0.1778 -0.5715)
							(mid 0.321484 -0.511984)
							(end 0.381 -0.3683)
						)
						(arc
							(start 0.381 0.3683)
							(mid 0.321484 0.511984)
							(end 0.1778 0.5715)
						)
					)
					(width 0)
					(fill yes)
				)
			)
		)
	)
	(footprint ""
		(layer "F.Cu")
		(at 199.840596 -114.573812)
		(property "Reference" "PU100"
			(at 0 0 0)
			(layer "F.SilkS")
			(hide yes)
			(effects
				(font
					(size 1.27 1.27)
				)
			)
		)
		(property "Value" "TPS53312RGTR-GP"
			(at 4.9784 -6.9342 0)
			(unlocked yes)
			(layer "F.Fab")
			(hide yes)
			(effects
				(font
					(size 1.016 1.016)
					(thickness 0.1524)
				)
			)
		)
		(property "Device Type" "QFN16G3-G1D7H40"
			(at 4.9784 -8.4582 0)
			(unlocked yes)
			(layer "F.Fab")
			(hide yes)
			(effects
				(font
					(size 1.016 1.016)
					(thickness 0.1524)
				)
			)
		)
		(duplicate_pad_numbers_are_jumpers no)
		(fp_line
			(start -2.5146 -2.5146)
			(end -2.5146 -1.2446)
			(stroke
				(width 0.1524)
				(type default)
			)
			(layer "F.SilkS")
		)
		(fp_line
			(start -2.5146 1.2446)
			(end -2.5146 2.5146)
			(stroke
				(width 0.1524)
				(type default)
			)
			(layer "F.SilkS")
		)
		(fp_line
			(start -2.5146 2.5146)
			(end -1.2446 2.5146)
			(stroke
				(width 0.1524)
				(type default)
			)
			(layer "F.SilkS")
		)
		(fp_line
			(start -2.262124 -0.750062)
			(end -2.770124 -0.750062)
			(stroke
				(width 0.1524)
				(type default)
			)
			(layer "F.SilkS")
		)
		(fp_line
			(start -1.2446 -2.5146)
			(end -2.5146 -2.5146)
			(stroke
				(width 0.1524)
				(type default)
			)
			(layer "F.SilkS")
		)
		(fp_line
			(start -0.249936 2.262124)
			(end -0.249936 3.024124)
			(stroke
				(width 0.1524)
				(type default)
			)
			(layer "F.SilkS")
		)
		(fp_line
			(start 1.2446 2.5146)
			(end 2.5146 2.5146)
			(stroke
				(width 0.1524)
				(type default)
			)
			(layer "F.SilkS")
		)
		(fp_line
			(start 2.262124 -0.249936)
			(end 2.770124 -0.249936)
			(stroke
				(width 0.1524)
				(type default)
			)
			(layer "F.SilkS")
		)
		(fp_line
			(start 2.5146 2.5146)
			(end 2.5146 1.2446)
			(stroke
				(width 0.1524)
				(type default)
			)
			(layer "F.SilkS")
		)
		(fp_poly
			(pts
				(xy 2.5146 -2.5146) (xy 1.2446 -2.5146) (xy 2.5146 -1.2446)
			)
			(stroke
				(width 0)
				(type default)
			)
			(fill yes)
			(layer "F.SilkS")
		)
		(fp_rect
			(start -1.4986 1.4986)
			(end 1.4986 -1.4986)
			(stroke
				(width 0)
				(type default)
			)
			(fill no)
			(layer "F.CrtYd")
		)
		(fp_poly
			(pts
				(xy 2.5146 -1.4986) (xy -1.4986 -1.4986) (xy -1.4986 1.4986) (xy 1.4986 1.4986) (xy 1.4986 -1.4859)
				(xy 2.5146 -1.4859) (xy 2.5146 2.5146) (xy -2.5146 2.5146) (xy -2.5146 -2.5146) (xy 2.5146 -2.5146)
			)
			(stroke
				(width 0)
				(type default)
			)
			(fill no)
			(layer "F.CrtYd")
		)
		(fp_rect
			(start -2.5146 2.5146)
			(end 2.5146 -2.5146)
			(stroke
				(width 0)
				(type default)
			)
			(fill no)
			(layer "F.Fab")
		)
		(pad "1" smd rect
			(at 0.750062 -1.550924)
			(size 0.3048 0.9144)
			(layers "F.Cu" "F.Mask" "F.Paste")
			(net "P1V5_E_VFB")
		)
		(pad "2" smd rect
			(at 0.249936 -1.538224)
			(size 0.3048 0.9398)
			(layers "F.Cu" "F.Mask" "F.Paste")
			(net "P1V5_E_VRG5")
		)
		(pad "3" smd rect
			(at -0.249936 -1.538224)
			(size 0.3048 0.9398)
			(layers "F.Cu" "F.Mask" "F.Paste")
			(net "P1V5_E_SS")
		)
		(pad "4" smd rect
			(at -0.750062 -1.550924)
			(size 0.3048 0.9144)
			(layers "F.Cu" "F.Mask" "F.Paste")
			(net "AGND_P1V5_E")
		)
		(pad "5" smd rect
			(at -1.550924 -0.750062)
			(size 0.9144 0.3048)
			(layers "F.Cu" "F.Mask" "F.Paste")
			(net "P1V5_E_PG")
		)
		(pad "6" smd rect
			(at -1.538224 -0.249936)
			(size 0.9398 0.3048)
			(layers "F.Cu" "F.Mask" "F.Paste")
			(net "P1V5_E_EN_R")
		)
		(pad "7" smd rect
			(at -1.538224 0.249936)
			(size 0.9398 0.3048)
			(layers "F.Cu" "F.Mask" "F.Paste")
			(net "GND")
		)
		(pad "8" smd rect
			(at -1.550924 0.750062)
			(size 0.9144 0.3048)
			(layers "F.Cu" "F.Mask" "F.Paste")
			(net "GND")
		)
		(pad "9" smd rect
			(at -0.750062 1.550924)
			(size 0.3048 0.9144)
			(layers "F.Cu" "F.Mask" "F.Paste")
			(net "P1V5_E_SW")
		)
		(pad "10" smd rect
			(at -0.249936 1.538224)
			(size 0.3048 0.9398)
			(layers "F.Cu" "F.Mask" "F.Paste")
			(net "P1V5_E_SW")
		)
		(pad "11" smd rect
			(at 0.249936 1.538224)
			(size 0.3048 0.9398)
			(layers "F.Cu" "F.Mask" "F.Paste")
			(net "P1V5_E_SW")
		)
		(pad "12" smd rect
			(at 0.750062 1.550924)
			(size 0.3048 0.9144)
			(layers "F.Cu" "F.Mask" "F.Paste")
			(net "P1V5_E_VBST")
		)
		(pad "13" smd rect
			(at 1.550924 0.750062)
			(size 0.9144 0.3048)
			(layers "F.Cu" "F.Mask" "F.Paste")
			(net "P1V5_E_VIN")
		)
		(pad "14" smd rect
			(at 1.538224 0.249936)
			(size 0.9398 0.3048)
			(layers "F.Cu" "F.Mask" "F.Paste")
			(net "P1V5_E_VIN")
		)
		(pad "15" smd rect
			(at 1.538224 -0.249936)
			(size 0.9398 0.3048)
			(layers "F.Cu" "F.Mask" "F.Paste")
			(net "P1V5_E_VCC")
		)
		(pad "16" smd rect
			(at 1.550924 -0.750062)
			(size 0.9144 0.3048)
			(layers "F.Cu" "F.Mask" "F.Paste")
			(net "P1V5_E_VO")
		)
		(pad "17" smd rect
			(at 0 0)
			(size 1.6764 1.6764)
			(layers "F.Cu" "F.Mask" "F.Paste")
			(net "GND")
		)
	)
	(footprint ""
		(layer "F.Cu")
		(at 99.20097 -115.697)
		(property "Reference" "TP265"
			(at 0 0 0)
			(layer "F.SilkS")
			(hide yes)
			(effects
				(font
					(size 1.27 1.27)
				)
			)
		)
		(property "Value" "TPAD28"
			(at 0.0127 -1.8034 0)
			(unlocked yes)
			(layer "F.Fab")
			(hide yes)
			(effects
				(font
					(size 1.016 1.016)
					(thickness 0.1524)
				)
			)
		)
		(property "Device Type" "TPAD28"
			(at 0.0127 -3.3274 0)
			(unlocked yes)
			(layer "F.Fab")
			(hide yes)
			(effects
				(font
					(size 1.016 1.016)
					(thickness 0.1524)
				)
			)
		)
		(duplicate_pad_numbers_are_jumpers no)
		(fp_poly
			(pts
				(arc
					(start 0.3556 0)
					(mid -0.3556 0)
					(end 0.3556 0)
				)
			)
			(stroke
				(width 0)
				(type default)
			)
			(fill no)
			(layer "F.CrtYd")
		)
		(fp_poly
			(pts
				(arc
					(start 0.6096 0)
					(mid -0.6096 0)
					(end 0.6096 0)
				)
			)
			(stroke
				(width 0)
				(type default)
			)
			(fill no)
			(layer "F.Fab")
		)
		(pad "1" smd circle
			(at 0 0)
			(size 0.7112 0.7112)
			(layers "F.Cu" "F.Mask" "F.Paste")
			(net "SIO_LOAD_IN")
		)
	)
	(footprint ""
		(layer "F.Cu")
		(at 310.388 -112.268 180)
		(property "Reference" "PR18"
			(at 0 0 180)
			(layer "F.SilkS")
			(hide yes)
			(effects
				(font
					(size 1.27 1.27)
				)
			)
		)
		(property "Value" "1K4R2F-1-GP"
			(at 0.064008 -3.993896 180)
			(unlocked yes)
			(layer "F.Fab")
			(hide yes)
			(effects
				(font
					(size 1.016 1.016)
					(thickness 0.1524)
				)
			)
		)
		(property "Device Type" "R402H16"
			(at 0.064008 -5.517896 180)
			(unlocked yes)
			(layer "F.Fab")
			(hide yes)
			(effects
				(font
					(size 1.016 1.016)
					(thickness 0.1524)
				)
			)
		)
		(duplicate_pad_numbers_are_jumpers no)
		(fp_line
			(start 0.508 -0.9398)
			(end -0.508 -0.9398)
			(stroke
				(width 0.1524)
				(type default)
			)
			(layer "F.SilkS")
		)
		(fp_line
			(start -0.508 -0.9398)
			(end -0.508 0.9398)
			(stroke
				(width 0.1524)
				(type default)
			)
			(layer "F.SilkS")
		)
		(fp_rect
			(start -0.508 0.9398)
			(end 0.508 -0.9398)
			(stroke
				(width 0)
				(type default)
			)
			(fill no)
			(layer "F.CrtYd")
		)
		(fp_rect
			(start -0.508 0.9398)
			(end 0.508 -0.9398)
			(stroke
				(width 0)
				(type default)
			)
			(fill no)
			(layer "F.Fab")
		)
		(pad "1" smd custom
			(at 0 -0.4445 180)
			(size 0.1397 0.1397)
			(layers "F.Cu" "F.Mask" "F.Paste")
			(net "P5V_STBY")
			(options
				(clearance outline)
				(anchor circle)
			)
			(primitives
				(gr_poly
					(pts
						(arc
							(start -0.1778 -0.2794)
							(mid -0.249642 -0.249642)
							(end -0.2794 -0.1778)
						)
						(arc
							(start -0.2794 0.1778)
							(mid -0.249642 0.249642)
							(end -0.1778 0.2794)
						)
						(arc
							(start 0.1778 0.2794)
							(mid 0.249642 0.249642)
							(end 0.2794 0.1778)
						)
						(arc
							(start 0.2794 -0.1778)
							(mid 0.249642 -0.249642)
							(end 0.1778 -0.2794)
						)
					)
					(width 0)
					(fill yes)
				)
			)
		)
		(pad "2" smd custom
			(at 0 0.4445 180)
			(size 0.1397 0.1397)
			(layers "F.Cu" "F.Mask" "F.Paste")
			(net "P3V3_STBY_EN")
			(options
				(clearance outline)
				(anchor circle)
			)
			(primitives
				(gr_poly
					(pts
						(arc
							(start -0.1778 -0.2794)
							(mid -0.249642 -0.249642)
							(end -0.2794 -0.1778)
						)
						(arc
							(start -0.2794 0.1778)
							(mid -0.249642 0.249642)
							(end -0.1778 0.2794)
						)
						(arc
							(start 0.1778 0.2794)
							(mid 0.249642 0.249642)
							(end 0.2794 0.1778)
						)
						(arc
							(start 0.2794 -0.1778)
							(mid 0.249642 -0.249642)
							(end 0.1778 -0.2794)
						)
					)
					(width 0)
					(fill yes)
				)
			)
		)
	)
	(footprint ""
		(layer "F.Cu")
		(at 277.740872 -225.116136 180)
		(property "Reference" "PC79"
			(at 0 0 180)
			(layer "F.SilkS")
			(hide yes)
			(effects
				(font
					(size 1.27 1.27)
				)
			)
		)
		(property "Value" "SC10U6D3V5KX-1GP"
			(at -0.0762 -6.1214 180)
			(unlocked yes)
			(layer "F.Fab")
			(hide yes)
			(effects
				(font
					(size 1.016 1.016)
					(thickness 0.1524)
				)
			)
		)
		(property "Device Type" "C805H54"
			(at -0.0762 -8.1534 180)
			(unlocked yes)
			(layer "F.Fab")
			(hide yes)
			(effects
				(font
					(size 1.016 1.016)
					(thickness 0.1524)
				)
			)
		)
		(duplicate_pad_numbers_are_jumpers no)
		(fp_line
			(start 0.635 0)
			(end -0.635 0)
			(stroke
				(width 0.508)
				(type default)
			)
			(layer "F.SilkS")
		)
		(fp_rect
			(start -0.9652 1.778)
			(end 0.9652 -1.778)
			(stroke
				(width 0)
				(type default)
			)
			(fill no)
			(layer "F.CrtYd")
		)
		(fp_poly
			(pts
				(xy -0.9652 -1.778) (xy 0.9652 -1.778) (xy 0.9652 1.778) (xy -0.9652 1.778)
			)
			(stroke
				(width 0)
				(type default)
			)
			(fill no)
			(layer "F.Fab")
		)
		(pad "1" smd rect
			(at 0 -0.9652 180)
			(size 1.397 1.143)
			(layers "F.Cu" "F.Mask" "F.Paste")
			(net "TPS74801_P1V53_STBY_IN")
		)
		(pad "2" smd rect
			(at 0 0.9652 180)
			(size 1.397 1.143)
			(layers "F.Cu" "F.Mask" "F.Paste")
			(net "GND")
		)
	)
)
